FILE_TYPE = CONNECTIVITY;
{Allegro Design Entry HDL 17.4-2019 S026 (4007227) 1/17/2022}
"PAGE_NUMBER" = 253;
0"NC";
1"SMB_INA230_1_3V3AUX_SDA_R";
2"SMB_INA230_1_3V3AUX_SCL_R";
3"SMB_INA230_4_3V3AUX_SCL_R";
4"SMB_INA230_2_3V3AUX_SCL_R";
5"SMB_INA230_2_3V3AUX_SDA_R";
6"SMB_INA230_3_3V3AUX_SCL_R";
7"SMB_INA230_3_3V3AUX_SDA_R";
8"SMB_INA230_3V3AUX_SCL";
9"SMB_INA230_5_3V3AUX_SCL_R";
10"SMB_INA230_4_3V3AUX_SDA_R";
11"SMB_INA230_7_3V3AUX_SCL_R";
12"SMB_INA230_5_3V3AUX_SDA_R";
13"SMB_INA230_6_3V3AUX_SCL_R";
14"SMB_INA230_8_3V3AUX_SDA_R";
15"SMB_INA230_8_3V3AUX_SCL_R";
16"SMB_INA230_7_3V3AUX_SDA_R";
17"SMB_INA230_6_3V3AUX_SDA_R";
18"SMB_INA230_3V3AUX_SDA";
%"Q_RES"
"1","(-4950,3675)","0","pure_quanta","I10";
;
LOCATION"R3588"
$SEC"1"
CDS_SEC"1"
WATTAGE"1/16W"
MATERIAL"CHIP"
TOLERANCE"1%"
VALUE"33.2"
PACK_TYPE"0402LF"
CDS_LIB"pure_quanta"
PART_NUMBER"CS03322FB03";
"B"
$PN"2"4;
"A"
$PN"1"8;
%"Q_RES"
"1","(-4950,3975)","0","pure_quanta","I11";
;
LOCATION"R3587"
$SEC"1"
CDS_SEC"1"
TOLERANCE"1%"
VALUE"33.2"
MATERIAL"CHIP"
CDS_LIB"pure_quanta"
WATTAGE"1/16W"
PACK_TYPE"0402LF"
PART_NUMBER"CS03322FB03";
"B"
$PN"2"1;
"A"
$PN"1"18;
%"Q_RES"
"1","(-4950,4025)","0","pure_quanta","I12";
;
LOCATION"R3586"
$SEC"1"
CDS_SEC"1"
WATTAGE"1/16W"
VALUE"33.2"
TOLERANCE"1%"
MATERIAL"CHIP"
PACK_TYPE"0402LF"
CDS_LIB"pure_quanta"
PART_NUMBER"CS03322FB03";
"B"
$PN"2"2;
"A"
$PN"1"8;
%"Q_RES"
"1","(-4950,2525)","0","pure_quanta","I23";
;
LOCATION"R1344"
$SEC"1"
CDS_SEC"1"
PACK_TYPE"0402LF"
VALUE"33.2"
MATERIAL"CHIP"
WATTAGE"1/16W"
TOLERANCE"1%"
CDS_LIB"pure_quanta"
PART_NUMBER"CS03322FB03";
"B"
$PN"2"13;
"A"
$PN"1"8;
%"Q_RES"
"1","(-4950,2475)","0","pure_quanta","I24";
;
LOCATION"R1345"
$SEC"1"
CDS_SEC"1"
TOLERANCE"1%"
MATERIAL"CHIP"
VALUE"33.2"
PACK_TYPE"0402LF"
WATTAGE"1/16W"
CDS_LIB"pure_quanta"
PART_NUMBER"CS03322FB03";
"B"
$PN"2"17;
"A"
$PN"1"18;
%"Q_RES"
"1","(-4950,2225)","0","pure_quanta","I25";
;
LOCATION"R1346"
$SEC"1"
CDS_SEC"1"
MATERIAL"CHIP"
WATTAGE"1/16W"
TOLERANCE"1%"
VALUE"33.2"
PACK_TYPE"0402LF"
CDS_LIB"pure_quanta"
PART_NUMBER"CS03322FB03";
"B"
$PN"2"11;
"A"
$PN"1"8;
%"Q_RES"
"1","(-4950,2175)","0","pure_quanta","I26";
;
LOCATION"R1347"
$SEC"1"
CDS_SEC"1"
MATERIAL"CHIP"
TOLERANCE"1%"
VALUE"33.2"
PACK_TYPE"0402LF"
WATTAGE"1/16W"
CDS_LIB"pure_quanta"
PART_NUMBER"CS03322FB03";
"B"
$PN"2"16;
"A"
$PN"1"18;
%"Q_RES"
"1","(-4950,1875)","0","pure_quanta","I27";
;
LOCATION"R1348"
$SEC"1"
CDS_SEC"1"
WATTAGE"1/16W"
PACK_TYPE"0402LF"
TOLERANCE"1%"
VALUE"33.2"
MATERIAL"CHIP"
CDS_LIB"pure_quanta"
PART_NUMBER"CS03322FB03";
"B"
$PN"2"15;
"A"
$PN"1"8;
%"Q_RES"
"1","(-4950,1825)","0","pure_quanta","I28";
;
LOCATION"R1349"
$SEC"1"
CDS_SEC"1"
VALUE"33.2"
MATERIAL"CHIP"
TOLERANCE"1%"
PACK_TYPE"0402LF"
WATTAGE"1/16W"
CDS_LIB"pure_quanta"
PART_NUMBER"CS03322FB03";
"B"
$PN"2"14;
"A"
$PN"1"18;
%"Q_RES"
"1","(-4950,2775)","0","pure_quanta","I3";
;
LOCATION"R3593"
$SEC"1"
CDS_SEC"1"
TOLERANCE"1%"
MATERIAL"CHIP"
VALUE"33.2"
PACK_TYPE"0402LF"
WATTAGE"1/16W"
CDS_LIB"pure_quanta"
PART_NUMBER"CS03322FB03";
"B"
$PN"2"12;
"A"
$PN"1"18;
%"Q_RES"
"1","(-4950,2825)","0","pure_quanta","I4";
;
LOCATION"R3592"
$SEC"1"
CDS_SEC"1"
WATTAGE"1/16W"
VALUE"33.2"
TOLERANCE"1%"
MATERIAL"CHIP"
PACK_TYPE"0402LF"
CDS_LIB"pure_quanta"
PART_NUMBER"CS03322FB03";
"B"
$PN"2"9;
"A"
$PN"1"8;
%"Q_RES"
"1","(-4925,3050)","0","pure_quanta","I5";
;
LOCATION"R3595"
$SEC"1"
CDS_SEC"1"
MATERIAL"CHIP"
TOLERANCE"1%"
VALUE"33.2"
WATTAGE"1/16W"
PACK_TYPE"0402LF"
CDS_LIB"pure_quanta"
PART_NUMBER"CS03322FB03";
"B"
$PN"2"10;
"A"
$PN"1"18;
%"Q_RES"
"1","(-4925,3100)","0","pure_quanta","I6";
;
LOCATION"R3594"
$SEC"1"
CDS_SEC"1"
TOLERANCE"1%"
MATERIAL"CHIP"
PACK_TYPE"0402LF"
VALUE"33.2"
WATTAGE"1/16W"
CDS_LIB"pure_quanta"
PART_NUMBER"CS03322FB03";
"B"
$PN"2"3;
"A"
$PN"1"8;
%"Q_RES"
"1","(-4950,3350)","0","pure_quanta","I7";
;
LOCATION"R3591"
$SEC"1"
CDS_SEC"1"
MATERIAL"CHIP"
TOLERANCE"1%"
VALUE"33.2"
CDS_LIB"pure_quanta"
WATTAGE"1/16W"
PACK_TYPE"0402LF"
PART_NUMBER"CS03322FB03";
"B"
$PN"2"7;
"A"
$PN"1"18;
%"Q_RES"
"1","(-4950,3400)","0","pure_quanta","I8";
;
LOCATION"R3590"
$SEC"1"
CDS_SEC"1"
WATTAGE"1/16W"
PACK_TYPE"0402LF"
VALUE"33.2"
TOLERANCE"1%"
MATERIAL"CHIP"
CDS_LIB"pure_quanta"
PART_NUMBER"CS03322FB03";
"B"
$PN"2"6;
"A"
$PN"1"8;
%"Q_RES"
"1","(-4950,3625)","0","pure_quanta","I9";
;
LOCATION"R3589"
$SEC"1"
CDS_SEC"1"
MATERIAL"CHIP"
TOLERANCE"1%"
VALUE"33.2"
CDS_LIB"pure_quanta"
PACK_TYPE"0402LF"
WATTAGE"1/16W"
PART_NUMBER"CS03322FB03";
"B"
$PN"2"5;
"A"
$PN"1"18;
END.
